(kicad_pcb
	(version 20241229)
	(generator "pcbnew")
	(generator_version "9.0")
	(general
		(thickness 1.61)
		(legacy_teardrops no)
	)
	(paper "A3")
	(title_block
		(title "RDIMM DDR5 Tester")
		(date "2026-05-21")
		(rev "2.2.0")
		(company "Antmicro")
		(comment 9 "footprints 392-396 of 796")
	)
	(layers
		(0 "F.Cu" signal)
		(4 "In1.Cu" power)
		(6 "In2.Cu" mixed)
		(8 "In3.Cu" power)
		(10 "In4.Cu" mixed)
		(12 "In5.Cu" power)
		(14 "In6.Cu" mixed)
		(16 "In7.Cu" power)
		(18 "In8.Cu" power)
		(20 "In9.Cu" mixed)
		(22 "In10.Cu" power)
		(2 "B.Cu" signal)
		(9 "F.Adhes" user "F.Adhesive")
		(11 "B.Adhes" user "B.Adhesive")
		(13 "F.Paste" user)
		(15 "B.Paste" user)
		(5 "F.SilkS" user "F.Silkscreen")
		(7 "B.SilkS" user "B.Silkscreen")
		(1 "F.Mask" user)
		(3 "B.Mask" user)
		(17 "Dwgs.User" user "User.Drawings")
		(19 "Cmts.User" user "User.Comments")
		(21 "Eco1.User" user "User.Eco1")
		(23 "Eco2.User" user "User.Eco2")
		(25 "Edge.Cuts" user)
		(27 "Margin" user)
		(31 "F.CrtYd" user "F.Courtyard")
		(29 "B.CrtYd" user "B.Courtyard")
		(35 "F.Fab" user)
		(33 "B.Fab" user)
	)
	(footprint "antmicro-footprints:R_0402_1005Metric"
		(layer "B.Cu")
		(at 126.325 142.762149 180)
		(descr "Resistor SMD 0402")
		(tags "resistor SMD 0402")
		(property "Reference" "R109"
			(at 2.2 -0.487851 0)
			(layer "B.SilkS")
			(effects
				(font
					(size 0.7 0.7)
					(thickness 0.15)
				)
				(justify left bottom mirror)
			)
		)
		(property "Value" "R_10k_0402"
			(at -1.011843 -1.772047 0)
			(layer "B.Fab")
			(effects
				(font
					(size 0.7 0.7)
					(thickness 0.15)
				)
				(justify left bottom mirror)
			)
		)
		(property "Datasheet" "https://www.bourns.com/docs/product-datasheets/cr.pdf"
			(at 0 0 180)
			(layer "F.Fab")
			(hide yes)
			(effects
				(font
					(size 1.27 1.27)
					(thickness 0.15)
				)
			)
		)
		(property "Manufacturer" "Bourns"
			(at 0 0 180)
			(unlocked yes)
			(layer "B.Fab")
			(hide yes)
			(effects
				(font
					(size 1 1)
					(thickness 0.15)
				)
				(justify mirror)
			)
		)
		(property "MPN" "CR0402-FX-1002GLF"
			(at 0 0 180)
			(unlocked yes)
			(layer "B.Fab")
			(hide yes)
			(effects
				(font
					(size 1 1)
					(thickness 0.15)
				)
				(justify mirror)
			)
		)
		(property "Val" "10k"
			(at 0 0 180)
			(unlocked yes)
			(layer "B.Fab")
			(hide yes)
			(effects
				(font
					(size 1 1)
					(thickness 0.15)
				)
				(justify mirror)
			)
		)
		(property "License" "Apache-2.0"
			(at 0 0 180)
			(unlocked yes)
			(layer "B.Fab")
			(hide yes)
			(effects
				(font
					(size 1 1)
					(thickness 0.15)
				)
				(justify mirror)
			)
		)
		(property "Author" "Antmicro"
			(at 0 0 180)
			(unlocked yes)
			(layer "B.Fab")
			(hide yes)
			(effects
				(font
					(size 1 1)
					(thickness 0.15)
				)
				(justify mirror)
			)
		)
		(property "Tolerance" "1%"
			(at 0 0 180)
			(unlocked yes)
			(layer "B.Fab")
			(hide yes)
			(effects
				(font
					(size 1 1)
					(thickness 0.15)
				)
				(justify mirror)
			)
		)
		(sheetname "/Ethernet/")
		(sheetfile "ethernet.kicad_sch")
		(attr smd)
		(fp_rect
			(start -0.925 0.47)
			(end 0.925 -0.47)
			(stroke
				(width 0.05)
				(type default)
			)
			(fill no)
			(layer "B.CrtYd")
		)
		(fp_rect
			(start -0.5 0.25)
			(end 0.5 -0.25)
			(stroke
				(width 0.15)
				(type solid)
			)
			(fill no)
			(layer "B.Fab")
		)
		(fp_text user "Author: Antmicro"
			(at -0.95 -4.169 0)
			(layer "B.Fab")
			(effects
				(font
					(size 0.7 0.7)
					(thickness 0.15)
				)
				(justify left bottom mirror)
			)
		)
		(fp_text user "${REFERENCE}"
			(at -0.95 -3.168 0)
			(layer "B.Fab")
			(effects
				(font
					(size 0.7 0.7)
					(thickness 0.15)
				)
				(justify left bottom mirror)
			)
		)
		(fp_text user "License: Apache-2.0"
			(at -0.95 -5.169 0)
			(layer "B.Fab")
			(effects
				(font
					(size 0.7 0.7)
					(thickness 0.15)
				)
				(justify left bottom mirror)
			)
		)
		(pad "1" smd roundrect
			(at -0.48 0 180)
			(size 0.59 0.64)
			(layers "B.Cu" "B.Mask" "B.Paste")
			(roundrect_rratio 0.25)
			(net 331 "/Ethernet/LED_LINK")
			(pintype "passive")
		)
		(pad "2" smd roundrect
			(at 0.48 0 180)
			(size 0.59 0.64)
			(layers "B.Cu" "B.Mask" "B.Paste")
			(roundrect_rratio 0.25)
			(net 797 "+1V8")
			(pintype "passive")
		)
	)
	(footprint "antmicro-footprints:C_0402_1005Metric"
		(layer "B.Cu")
		(at 139.224499 145.6)
		(descr "Capacitor SMD 0402")
		(tags "capacitor SMD 0402")
		(property "Reference" "C139"
			(at 1.005501 0.43 0)
			(layer "B.SilkS")
			(effects
				(font
					(size 0.7 0.7)
					(thickness 0.15)
				)
				(justify right bottom mirror)
			)
		)
		(property "Value" "C_4u7_0402"
			(at -1.022927 -2.155213 0)
			(layer "B.Fab")
			(effects
				(font
					(size 0.7 0.7)
					(thickness 0.15)
				)
				(justify right bottom mirror)
			)
		)
		(property "Datasheet" "https://www.murata.com/products/productdetail?partno=GRM155R61A475MEAA%23"
			(at 0 0 0)
			(layer "F.Fab")
			(hide yes)
			(effects
				(font
					(size 1.27 1.27)
					(thickness 0.15)
				)
			)
		)
		(property "Manufacturer" "Murata"
			(at 0 0 0)
			(unlocked yes)
			(layer "B.Fab")
			(hide yes)
			(effects
				(font
					(size 1 1)
					(thickness 0.15)
				)
				(justify mirror)
			)
		)
		(property "MPN" "GRM155R61A475MEAAD"
			(at 0 0 0)
			(unlocked yes)
			(layer "B.Fab")
			(hide yes)
			(effects
				(font
					(size 1 1)
					(thickness 0.15)
				)
				(justify mirror)
			)
		)
		(property "Val" "4u7"
			(at 0 0 0)
			(unlocked yes)
			(layer "B.Fab")
			(hide yes)
			(effects
				(font
					(size 1 1)
					(thickness 0.15)
				)
				(justify mirror)
			)
		)
		(property "License" "Apache-2.0"
			(at 0 0 0)
			(unlocked yes)
			(layer "B.Fab")
			(hide yes)
			(effects
				(font
					(size 1 1)
					(thickness 0.15)
				)
				(justify mirror)
			)
		)
		(property "Author" "Antmicro"
			(at 0 0 0)
			(unlocked yes)
			(layer "B.Fab")
			(hide yes)
			(effects
				(font
					(size 1 1)
					(thickness 0.15)
				)
				(justify mirror)
			)
		)
		(property "Voltage" ""
			(at 0 0 0)
			(unlocked yes)
			(layer "B.Fab")
			(hide yes)
			(effects
				(font
					(size 1 1)
					(thickness 0.15)
				)
				(justify mirror)
			)
		)
		(property "Dielectric" ""
			(at 0 0 0)
			(unlocked yes)
			(layer "B.Fab")
			(hide yes)
			(effects
				(font
					(size 1 1)
					(thickness 0.15)
				)
				(justify mirror)
			)
		)
		(sheetname "/Ethernet/")
		(sheetfile "ethernet.kicad_sch")
		(attr smd)
		(fp_rect
			(start -0.925 0.47)
			(end 0.925 -0.47)
			(stroke
				(width 0.05)
				(type default)
			)
			(fill no)
			(layer "B.CrtYd")
		)
		(fp_line
			(start -0.494 -0.248)
			(end -0.494 0.25)
			(stroke
				(width 0.15)
				(type solid)
			)
			(layer "B.Fab")
		)
		(fp_line
			(start -0.494 0.25)
			(end 0.504 0.25)
			(stroke
				(width 0.15)
				(type solid)
			)
			(layer "B.Fab")
		)
		(fp_line
			(start 0.504 -0.248)
			(end -0.494 -0.248)
			(stroke
				(width 0.15)
				(type solid)
			)
			(layer "B.Fab")
		)
		(fp_line
			(start 0.504 0.25)
			(end 0.504 -0.248)
			(stroke
				(width 0.15)
				(type solid)
			)
			(layer "B.Fab")
		)
		(fp_text user "${REFERENCE}"
			(at -0.939 -4.599 180)
			(layer "B.Fab")
			(effects
				(font
					(size 0.7 0.7)
					(thickness 0.15)
				)
				(justify left bottom mirror)
			)
		)
		(fp_text user "License: Apache-2.0"
			(at -0.939 -5.799 180)
			(layer "B.Fab")
			(effects
				(font
					(size 0.7 0.7)
					(thickness 0.15)
				)
				(justify left bottom mirror)
			)
		)
		(fp_text user "Author: Antmicro"
			(at -0.939 -3.399 180)
			(layer "B.Fab")
			(effects
				(font
					(size 0.7 0.7)
					(thickness 0.15)
				)
				(justify left bottom mirror)
			)
		)
		(pad "1" smd roundrect
			(at -0.48 0)
			(size 0.59 0.64)
			(layers "B.Cu" "B.Mask" "B.Paste")
			(roundrect_rratio 0.25)
			(net 150 "+1V2")
			(pintype "passive")
		)
		(pad "2" smd roundrect
			(at 0.48 0)
			(size 0.59 0.64)
			(layers "B.Cu" "B.Mask" "B.Paste")
			(roundrect_rratio 0.25)
			(net 1 "GND")
			(pintype "passive")
		)
	)
	(footprint "antmicro-footprints:C_0402_1005Metric"
		(layer "B.Cu")
		(at 139.224499 146.6)
		(descr "Capacitor SMD 0402")
		(tags "capacitor SMD 0402")
		(property "Reference" "C142"
			(at 1.005501 0.43 0)
			(layer "B.SilkS")
			(effects
				(font
					(size 0.7 0.7)
					(thickness 0.15)
				)
				(justify right bottom mirror)
			)
		)
		(property "Value" "C_470n_0402"
			(at -1.022927 -2.155213 0)
			(layer "B.Fab")
			(effects
				(font
					(size 0.7 0.7)
					(thickness 0.15)
				)
				(justify right bottom mirror)
			)
		)
		(property "Datasheet" "https://product.tdk.com/en/search/capacitor/ceramic/mlcc/info?part_no=C1005X5R1E474M050BB"
			(at 0 0 0)
			(layer "F.Fab")
			(hide yes)
			(effects
				(font
					(size 1.27 1.27)
					(thickness 0.15)
				)
			)
		)
		(property "Manufacturer" "TDK"
			(at 0 0 0)
			(unlocked yes)
			(layer "B.Fab")
			(hide yes)
			(effects
				(font
					(size 1 1)
					(thickness 0.15)
				)
				(justify mirror)
			)
		)
		(property "MPN" "C1005X5R1E474M050BB"
			(at 0 0 0)
			(unlocked yes)
			(layer "B.Fab")
			(hide yes)
			(effects
				(font
					(size 1 1)
					(thickness 0.15)
				)
				(justify mirror)
			)
		)
		(property "Val" "470n"
			(at 0 0 0)
			(unlocked yes)
			(layer "B.Fab")
			(hide yes)
			(effects
				(font
					(size 1 1)
					(thickness 0.15)
				)
				(justify mirror)
			)
		)
		(property "License" "Apache-2.0"
			(at 0 0 0)
			(unlocked yes)
			(layer "B.Fab")
			(hide yes)
			(effects
				(font
					(size 1 1)
					(thickness 0.15)
				)
				(justify mirror)
			)
		)
		(property "Author" "Antmicro"
			(at 0 0 0)
			(unlocked yes)
			(layer "B.Fab")
			(hide yes)
			(effects
				(font
					(size 1 1)
					(thickness 0.15)
				)
				(justify mirror)
			)
		)
		(property "Voltage" ""
			(at 0 0 0)
			(unlocked yes)
			(layer "B.Fab")
			(hide yes)
			(effects
				(font
					(size 1 1)
					(thickness 0.15)
				)
				(justify mirror)
			)
		)
		(property "Dielectric" ""
			(at 0 0 0)
			(unlocked yes)
			(layer "B.Fab")
			(hide yes)
			(effects
				(font
					(size 1 1)
					(thickness 0.15)
				)
				(justify mirror)
			)
		)
		(sheetname "/Ethernet/")
		(sheetfile "ethernet.kicad_sch")
		(attr smd)
		(fp_rect
			(start -0.925 0.47)
			(end 0.925 -0.47)
			(stroke
				(width 0.05)
				(type default)
			)
			(fill no)
			(layer "B.CrtYd")
		)
		(fp_line
			(start -0.494 -0.248)
			(end -0.494 0.25)
			(stroke
				(width 0.15)
				(type solid)
			)
			(layer "B.Fab")
		)
		(fp_line
			(start -0.494 0.25)
			(end 0.504 0.25)
			(stroke
				(width 0.15)
				(type solid)
			)
			(layer "B.Fab")
		)
		(fp_line
			(start 0.504 -0.248)
			(end -0.494 -0.248)
			(stroke
				(width 0.15)
				(type solid)
			)
			(layer "B.Fab")
		)
		(fp_line
			(start 0.504 0.25)
			(end 0.504 -0.248)
			(stroke
				(width 0.15)
				(type solid)
			)
			(layer "B.Fab")
		)
		(fp_text user "License: Apache-2.0"
			(at -0.939 -5.799 180)
			(layer "B.Fab")
			(effects
				(font
					(size 0.7 0.7)
					(thickness 0.15)
				)
				(justify left bottom mirror)
			)
		)
		(fp_text user "Author: Antmicro"
			(at -0.939 -3.399 180)
			(layer "B.Fab")
			(effects
				(font
					(size 0.7 0.7)
					(thickness 0.15)
				)
				(justify left bottom mirror)
			)
		)
		(fp_text user "${REFERENCE}"
			(at -0.939 -4.599 180)
			(layer "B.Fab")
			(effects
				(font
					(size 0.7 0.7)
					(thickness 0.15)
				)
				(justify left bottom mirror)
			)
		)
		(pad "1" smd roundrect
			(at -0.48 0)
			(size 0.59 0.64)
			(layers "B.Cu" "B.Mask" "B.Paste")
			(roundrect_rratio 0.25)
			(net 150 "+1V2")
			(pintype "passive")
		)
		(pad "2" smd roundrect
			(at 0.48 0)
			(size 0.59 0.64)
			(layers "B.Cu" "B.Mask" "B.Paste")
			(roundrect_rratio 0.25)
			(net 1 "GND")
			(pintype "passive")
		)
	)
	(footprint "antmicro-footprints:C_0402_1005Metric"
		(layer "B.Cu")
		(at 136.724499 138.749 90)
		(descr "Capacitor SMD 0402")
		(tags "capacitor SMD 0402")
		(property "Reference" "C146"
			(at 1.176157 0.344672 90)
			(layer "B.SilkS")
			(effects
				(font
					(size 0.7 0.7)
					(thickness 0.15)
				)
				(justify right bottom mirror)
			)
		)
		(property "Value" "C_4u7_0402"
			(at -1.022927 -2.155213 90)
			(layer "B.Fab")
			(effects
				(font
					(size 0.7 0.7)
					(thickness 0.15)
				)
				(justify right bottom mirror)
			)
		)
		(property "Datasheet" "https://www.murata.com/products/productdetail?partno=GRM155R61A475MEAA%23"
			(at 0 0 90)
			(layer "F.Fab")
			(hide yes)
			(effects
				(font
					(size 1.27 1.27)
					(thickness 0.15)
				)
			)
		)
		(property "Manufacturer" "Murata"
			(at 0 0 90)
			(unlocked yes)
			(layer "B.Fab")
			(hide yes)
			(effects
				(font
					(size 1 1)
					(thickness 0.15)
				)
				(justify mirror)
			)
		)
		(property "MPN" "GRM155R61A475MEAAD"
			(at 0 0 90)
			(unlocked yes)
			(layer "B.Fab")
			(hide yes)
			(effects
				(font
					(size 1 1)
					(thickness 0.15)
				)
				(justify mirror)
			)
		)
		(property "Val" "4u7"
			(at 0 0 90)
			(unlocked yes)
			(layer "B.Fab")
			(hide yes)
			(effects
				(font
					(size 1 1)
					(thickness 0.15)
				)
				(justify mirror)
			)
		)
		(property "License" "Apache-2.0"
			(at 0 0 90)
			(unlocked yes)
			(layer "B.Fab")
			(hide yes)
			(effects
				(font
					(size 1 1)
					(thickness 0.15)
				)
				(justify mirror)
			)
		)
		(property "Author" "Antmicro"
			(at 0 0 90)
			(unlocked yes)
			(layer "B.Fab")
			(hide yes)
			(effects
				(font
					(size 1 1)
					(thickness 0.15)
				)
				(justify mirror)
			)
		)
		(property "Voltage" ""
			(at 0 0 90)
			(unlocked yes)
			(layer "B.Fab")
			(hide yes)
			(effects
				(font
					(size 1 1)
					(thickness 0.15)
				)
				(justify mirror)
			)
		)
		(property "Dielectric" ""
			(at 0 0 90)
			(unlocked yes)
			(layer "B.Fab")
			(hide yes)
			(effects
				(font
					(size 1 1)
					(thickness 0.15)
				)
				(justify mirror)
			)
		)
		(sheetname "/Ethernet/")
		(sheetfile "ethernet.kicad_sch")
		(attr smd)
		(fp_rect
			(start -0.925 0.47)
			(end 0.925 -0.47)
			(stroke
				(width 0.05)
				(type default)
			)
			(fill no)
			(layer "B.CrtYd")
		)
		(fp_line
			(start 0.504 -0.248)
			(end -0.494 -0.248)
			(stroke
				(width 0.15)
				(type solid)
			)
			(layer "B.Fab")
		)
		(fp_line
			(start -0.494 -0.248)
			(end -0.494 0.25)
			(stroke
				(width 0.15)
				(type solid)
			)
			(layer "B.Fab")
		)
		(fp_line
			(start 0.504 0.25)
			(end 0.504 -0.248)
			(stroke
				(width 0.15)
				(type solid)
			)
			(layer "B.Fab")
		)
		(fp_line
			(start -0.494 0.25)
			(end 0.504 0.25)
			(stroke
				(width 0.15)
				(type solid)
			)
			(layer "B.Fab")
		)
		(fp_text user "${REFERENCE}"
			(at -0.939 -4.599 270)
			(layer "B.Fab")
			(effects
				(font
					(size 0.7 0.7)
					(thickness 0.15)
				)
				(justify left bottom mirror)
			)
		)
		(fp_text user "License: Apache-2.0"
			(at -0.939 -5.799 270)
			(layer "B.Fab")
			(effects
				(font
					(size 0.7 0.7)
					(thickness 0.15)
				)
				(justify left bottom mirror)
			)
		)
		(fp_text user "Author: Antmicro"
			(at -0.939 -3.399 270)
			(layer "B.Fab")
			(effects
				(font
					(size 0.7 0.7)
					(thickness 0.15)
				)
				(justify left bottom mirror)
			)
		)
		(pad "1" smd roundrect
			(at -0.48 0 90)
			(size 0.59 0.64)
			(layers "B.Cu" "B.Mask" "B.Paste")
			(roundrect_rratio 0.25)
			(net 95 "/Ethernet/AVDDL")
			(pintype "passive")
		)
		(pad "2" smd roundrect
			(at 0.48 0 90)
			(size 0.59 0.64)
			(layers "B.Cu" "B.Mask" "B.Paste")
			(roundrect_rratio 0.25)
			(net 1 "GND")
			(pintype "passive")
		)
	)
	(footprint "antmicro-footprints:C_0402_1005Metric"
		(layer "B.Cu")
		(at 134.433171 146.453992 90)
		(descr "Capacitor SMD 0402")
		(tags "capacitor SMD 0402")
		(property "Reference" "C145"
			(at -3.914008 0.202829 90)
			(layer "B.SilkS")
			(effects
				(font
					(size 0.7 0.7)
					(thickness 0.15)
				)
				(justify right bottom mirror)
			)
		)
		(property "Value" "C_470n_0402"
			(at -1.022927 -2.155213 90)
			(layer "B.Fab")
			(effects
				(font
					(size 0.7 0.7)
					(thickness 0.15)
				)
				(justify right bottom mirror)
			)
		)
		(property "Datasheet" "https://product.tdk.com/en/search/capacitor/ceramic/mlcc/info?part_no=C1005X5R1E474M050BB"
			(at 0 0 90)
			(layer "F.Fab")
			(hide yes)
			(effects
				(font
					(size 1.27 1.27)
					(thickness 0.15)
				)
			)
		)
		(property "Manufacturer" "TDK"
			(at 0 0 90)
			(unlocked yes)
			(layer "B.Fab")
			(hide yes)
			(effects
				(font
					(size 1 1)
					(thickness 0.15)
				)
				(justify mirror)
			)
		)
		(property "MPN" "C1005X5R1E474M050BB"
			(at 0 0 90)
			(unlocked yes)
			(layer "B.Fab")
			(hide yes)
			(effects
				(font
					(size 1 1)
					(thickness 0.15)
				)
				(justify mirror)
			)
		)
		(property "Val" "470n"
			(at 0 0 90)
			(unlocked yes)
			(layer "B.Fab")
			(hide yes)
			(effects
				(font
					(size 1 1)
					(thickness 0.15)
				)
				(justify mirror)
			)
		)
		(property "License" "Apache-2.0"
			(at 0 0 90)
			(unlocked yes)
			(layer "B.Fab")
			(hide yes)
			(effects
				(font
					(size 1 1)
					(thickness 0.15)
				)
				(justify mirror)
			)
		)
		(property "Author" "Antmicro"
			(at 0 0 90)
			(unlocked yes)
			(layer "B.Fab")
			(hide yes)
			(effects
				(font
					(size 1 1)
					(thickness 0.15)
				)
				(justify mirror)
			)
		)
		(property "Voltage" ""
			(at 0 0 90)
			(unlocked yes)
			(layer "B.Fab")
			(hide yes)
			(effects
				(font
					(size 1 1)
					(thickness 0.15)
				)
				(justify mirror)
			)
		)
		(property "Dielectric" ""
			(at 0 0 90)
			(unlocked yes)
			(layer "B.Fab")
			(hide yes)
			(effects
				(font
					(size 1 1)
					(thickness 0.15)
				)
				(justify mirror)
			)
		)
		(sheetname "/Ethernet/")
		(sheetfile "ethernet.kicad_sch")
		(attr smd)
		(fp_rect
			(start -0.925 0.47)
			(end 0.925 -0.47)
			(stroke
				(width 0.05)
				(type default)
			)
			(fill no)
			(layer "B.CrtYd")
		)
		(fp_line
			(start 0.504 -0.248)
			(end -0.494 -0.248)
			(stroke
				(width 0.15)
				(type solid)
			)
			(layer "B.Fab")
		)
		(fp_line
			(start -0.494 -0.248)
			(end -0.494 0.25)
			(stroke
				(width 0.15)
				(type solid)
			)
			(layer "B.Fab")
		)
		(fp_line
			(start 0.504 0.25)
			(end 0.504 -0.248)
			(stroke
				(width 0.15)
				(type solid)
			)
			(layer "B.Fab")
		)
		(fp_line
			(start -0.494 0.25)
			(end 0.504 0.25)
			(stroke
				(width 0.15)
				(type solid)
			)
			(layer "B.Fab")
		)
		(fp_text user "${REFERENCE}"
			(at -0.939 -4.599 270)
			(layer "B.Fab")
			(effects
				(font
					(size 0.7 0.7)
					(thickness 0.15)
				)
				(justify left bottom mirror)
			)
		)
		(fp_text user "Author: Antmicro"
			(at -0.939 -3.399 270)
			(layer "B.Fab")
			(effects
				(font
					(size 0.7 0.7)
					(thickness 0.15)
				)
				(justify left bottom mirror)
			)
		)
		(fp_text user "License: Apache-2.0"
			(at -0.939 -5.799 270)
			(layer "B.Fab")
			(effects
				(font
					(size 0.7 0.7)
					(thickness 0.15)
				)
				(justify left bottom mirror)
			)
		)
		(pad "1" smd roundrect
			(at -0.48 0 90)
			(size 0.59 0.64)
			(layers "B.Cu" "B.Mask" "B.Paste")
			(roundrect_rratio 0.25)
			(net 150 "+1V2")
			(pintype "passive")
		)
		(pad "2" smd roundrect
			(at 0.48 0 90)
			(size 0.59 0.64)
			(layers "B.Cu" "B.Mask" "B.Paste")
			(roundrect_rratio 0.25)
			(net 1 "GND")
			(pintype "passive")
		)
	)
)
